# S9S_MB_2U (Grand Teton) — schematic netlist excerpt (pin names and nets, part order shuffled) for the footprints in the layout excerpt that follows; sources: Cadence DE-HDL packaged netlist, KiCad conversion of 03242023_DA0F0TMBIJ0_F0T_Motherboard_J_brd_V01_OCP.brd

R991  Q_RES  2K 1% CHIP  pkg 0402LF  page 219 : A = FM_AUX_SW_EN ; B = GND
R537  Q_RES  1K 1% CHIP  pkg 0402LF  page 231 : A = PCA9548_PCIE3_ADDR2 ; B = GND

(kicad_pcb
	(version 20260206)
	(generator "pcbnew")
	(generator_version "10.0")
	(general
		(thickness 1.6)
		(legacy_teardrops no)
	)
	(paper "A4")
	(title_block
		(title "03242023_DA0F0TMBIJ0_F0T_Motherboard_J_brd_V01_OCP.brd")
		(comment 1 "Grand Teton / footprints 1345-1346 of 6105")
	)
	(layers
		(0 "F.Cu" signal "TOP")
		(4 "In1.Cu" signal "GND")
		(6 "In2.Cu" signal "IN1")
		(8 "In3.Cu" signal "GND1")
		(10 "In4.Cu" signal "IN2")
		(12 "In5.Cu" signal "GND2")
		(14 "In6.Cu" signal "IN3")
		(16 "In7.Cu" signal "GND3")
		(18 "In8.Cu" signal "VCC")
		(20 "In9.Cu" signal "VCC1")
		(22 "In10.Cu" signal "GND4")
		(24 "In11.Cu" signal "IN4")
		(26 "In12.Cu" signal "GND5")
		(28 "In13.Cu" signal "IN5")
		(30 "In14.Cu" signal "GND6")
		(32 "In15.Cu" signal "IN6")
		(34 "In16.Cu" signal "GND7")
		(2 "B.Cu" signal "BOTTOM")
		(9 "F.Adhes" user "F.Adhesive")
		(11 "B.Adhes" user "B.Adhesive")
		(13 "F.Paste" user "Package Geometry/Pastemask Top")
		(15 "B.Paste" user "Package Geometry/Pastemask Bottom")
		(5 "F.SilkS" user "Ref Des/Silkscreen Top")
		(7 "B.SilkS" user "Ref Des/Silkscreen Bottom")
		(1 "F.Mask" user "Board Geometry/Soldermask Top")
		(3 "B.Mask" user "Board Geometry/Soldermask Bottom")
		(17 "Dwgs.User" user "User.Drawings")
		(19 "Cmts.User" user "User.Comments")
		(21 "Eco1.User" user "User.Eco1")
		(23 "Eco2.User" user "User.Eco2")
		(25 "Edge.Cuts" user "Board Geometry/Outline")
		(27 "Margin" user)
		(31 "F.CrtYd" user "Package Geometry/Place Bound Top")
		(29 "B.CrtYd" user "Package Geometry/Place Bound Bottom")
		(35 "F.Fab" user "Ref Des/Assembly Top")
		(33 "B.Fab" user "Ref Des/Assembly Bottom")
	)
	(footprint ""
		(layer "F.Cu")
		(at 171.50588 -130.266948 90)
		(property "Reference" "R991"
			(at 0 0 90)
			(layer "F.SilkS")
			(hide yes)
			(effects
				(font
					(size 1.27 1.27)
				)
			)
		)
		(property "Value" ""
			(at 0 0 90)
			(layer "F.Fab")
			(effects
				(font
					(size 1.27 1.27)
				)
			)
		)
		(duplicate_pad_numbers_are_jumpers no)
		(fp_line
			(start 0.7874 -0.4064)
			(end 0.7874 0.4064)
			(stroke
				(width 0.1524)
				(type default)
			)
			(layer "F.SilkS")
		)
		(fp_line
			(start -0.7874 -0.4064)
			(end 0.7874 -0.4064)
			(stroke
				(width 0.1524)
				(type default)
			)
			(layer "F.SilkS")
		)
		(fp_line
			(start 0.7874 0.4064)
			(end -0.7874 0.4064)
			(stroke
				(width 0.1524)
				(type default)
			)
			(layer "F.SilkS")
		)
		(fp_line
			(start -0.7874 0.4064)
			(end -0.7874 -0.4064)
			(stroke
				(width 0.1524)
				(type default)
			)
			(layer "F.SilkS")
		)
		(fp_line
			(start -0.12065 -0.305054)
			(end -0.12065 -0.2794)
			(stroke
				(width 0.1)
				(type default)
			)
			(layer "F.Fab")
		)
		(fp_line
			(start -0.67945 -0.305054)
			(end -0.12065 -0.305054)
			(stroke
				(width 0.1)
				(type default)
			)
			(layer "F.Fab")
		)
		(fp_line
			(start 0.67945 -0.3048)
			(end 0.67945 0.3048)
			(stroke
				(width 0.1)
				(type default)
			)
			(layer "F.Fab")
		)
		(fp_line
			(start 0.12065 -0.3048)
			(end 0.67945 -0.3048)
			(stroke
				(width 0.1)
				(type default)
			)
			(layer "F.Fab")
		)
		(fp_line
			(start 0.12065 -0.2794)
			(end 0.12065 -0.3048)
			(stroke
				(width 0.1)
				(type default)
			)
			(layer "F.Fab")
		)
		(fp_line
			(start -0.12065 -0.2794)
			(end 0.12065 -0.2794)
			(stroke
				(width 0.1)
				(type default)
			)
			(layer "F.Fab")
		)
		(fp_line
			(start 0.120396 0.2794)
			(end -0.12065 0.2794)
			(stroke
				(width 0.1)
				(type default)
			)
			(layer "F.Fab")
		)
		(fp_line
			(start -0.12065 0.2794)
			(end -0.12065 0.3048)
			(stroke
				(width 0.1)
				(type default)
			)
			(layer "F.Fab")
		)
		(fp_line
			(start 0.67945 0.3048)
			(end 0.120396 0.3048)
			(stroke
				(width 0.1)
				(type default)
			)
			(layer "F.Fab")
		)
		(fp_line
			(start 0.120396 0.3048)
			(end 0.120396 0.2794)
			(stroke
				(width 0.1)
				(type default)
			)
			(layer "F.Fab")
		)
		(fp_line
			(start -0.12065 0.3048)
			(end -0.67945 0.3048)
			(stroke
				(width 0.1)
				(type default)
			)
			(layer "F.Fab")
		)
		(fp_line
			(start -0.67945 0.3048)
			(end -0.67945 -0.305054)
			(stroke
				(width 0.1)
				(type default)
			)
			(layer "F.Fab")
		)
		(pad "1" smd circle
			(at -0.40005 0 90)
			(size 0 0)
			(layers "F.Cu" "F.Mask" "F.Paste")
			(net "FM_AUX_SW_EN")
		)
		(pad "2" smd circle
			(at 0.40005 0 90)
			(size 0 0)
			(layers "F.Cu" "F.Mask" "F.Paste")
			(net "GND")
		)
	)
	(footprint ""
		(layer "F.Cu")
		(at 128.401572 -137.114026)
		(property "Reference" "R537"
			(at 0 0 0)
			(layer "F.SilkS")
			(hide yes)
			(effects
				(font
					(size 1.27 1.27)
				)
			)
		)
		(property "Value" ""
			(at 0 0 0)
			(layer "F.Fab")
			(effects
				(font
					(size 1.27 1.27)
				)
			)
		)
		(duplicate_pad_numbers_are_jumpers no)
		(fp_line
			(start -0.7874 -0.4064)
			(end 0.7874 -0.4064)
			(stroke
				(width 0.1524)
				(type default)
			)
			(layer "F.SilkS")
		)
		(fp_line
			(start -0.7874 0.4064)
			(end -0.7874 -0.4064)
			(stroke
				(width 0.1524)
				(type default)
			)
			(layer "F.SilkS")
		)
		(fp_line
			(start 0.7874 -0.4064)
			(end 0.7874 0.4064)
			(stroke
				(width 0.1524)
				(type default)
			)
			(layer "F.SilkS")
		)
		(fp_line
			(start 0.7874 0.4064)
			(end -0.7874 0.4064)
			(stroke
				(width 0.1524)
				(type default)
			)
			(layer "F.SilkS")
		)
		(fp_line
			(start -0.67945 -0.305054)
			(end -0.12065 -0.305054)
			(stroke
				(width 0.1)
				(type default)
			)
			(layer "F.Fab")
		)
		(fp_line
			(start -0.67945 0.3048)
			(end -0.67945 -0.305054)
			(stroke
				(width 0.1)
				(type default)
			)
			(layer "F.Fab")
		)
		(fp_line
			(start -0.12065 -0.305054)
			(end -0.12065 -0.2794)
			(stroke
				(width 0.1)
				(type default)
			)
			(layer "F.Fab")
		)
		(fp_line
			(start -0.12065 -0.2794)
			(end 0.12065 -0.2794)
			(stroke
				(width 0.1)
				(type default)
			)
			(layer "F.Fab")
		)
		(fp_line
			(start -0.12065 0.2794)
			(end -0.12065 0.3048)
			(stroke
				(width 0.1)
				(type default)
			)
			(layer "F.Fab")
		)
		(fp_line
			(start -0.12065 0.3048)
			(end -0.67945 0.3048)
			(stroke
				(width 0.1)
				(type default)
			)
			(layer "F.Fab")
		)
		(fp_line
			(start 0.120396 0.2794)
			(end -0.12065 0.2794)
			(stroke
				(width 0.1)
				(type default)
			)
			(layer "F.Fab")
		)
		(fp_line
			(start 0.120396 0.3048)
			(end 0.120396 0.2794)
			(stroke
				(width 0.1)
				(type default)
			)
			(layer "F.Fab")
		)
		(fp_line
			(start 0.12065 -0.3048)
			(end 0.67945 -0.3048)
			(stroke
				(width 0.1)
				(type default)
			)
			(layer "F.Fab")
		)
		(fp_line
			(start 0.12065 -0.2794)
			(end 0.12065 -0.3048)
			(stroke
				(width 0.1)
				(type default)
			)
			(layer "F.Fab")
		)
		(fp_line
			(start 0.67945 -0.3048)
			(end 0.67945 0.3048)
			(stroke
				(width 0.1)
				(type default)
			)
			(layer "F.Fab")
		)
		(fp_line
			(start 0.67945 0.3048)
			(end 0.120396 0.3048)
			(stroke
				(width 0.1)
				(type default)
			)
			(layer "F.Fab")
		)
		(pad "1" smd circle
			(at -0.40005 0)
			(size 0 0)
			(layers "F.Cu" "F.Mask" "F.Paste")
			(net "PCA9548_PCIE3_ADDR2")
		)
		(pad "2" smd circle
			(at 0.40005 0)
			(size 0 0)
			(layers "F.Cu" "F.Mask" "F.Paste")
			(net "GND")
		)
	)
)
